(kicad_pcb
	(version 20260206)
	(generator "pcbnew")
	(generator_version "10.0")
	(general
		(thickness 1.6)
		(legacy_teardrops no)
	)
	(paper "A4")
	(title_block
		(title "12092022_DA0F0TMDCD0_F0T_Management_Board_D_brd_V3_OCP.brd")
		(comment 1 "Grand Teton / footprints 945-950 of 1440")
	)
	(layers
		(0 "F.Cu" signal "TOP")
		(4 "In1.Cu" signal "GND")
		(6 "In2.Cu" signal "IN1")
		(8 "In3.Cu" signal "GND1")
		(10 "In4.Cu" signal "IN2")
		(12 "In5.Cu" signal "VCC")
		(14 "In6.Cu" signal "VCC1")
		(16 "In7.Cu" signal "IN3")
		(18 "In8.Cu" signal "GND2")
		(20 "In9.Cu" signal "IN4")
		(22 "In10.Cu" signal "GND3")
		(2 "B.Cu" signal "BOTTOM")
		(9 "F.Adhes" user "F.Adhesive")
		(11 "B.Adhes" user "B.Adhesive")
		(13 "F.Paste" user "Package Geometry/Pastemask Top")
		(15 "B.Paste" user "Package Geometry/Pastemask Bottom")
		(5 "F.SilkS" user "Ref Des/Silkscreen Top")
		(7 "B.SilkS" user "Ref Des/Silkscreen Bottom")
		(1 "F.Mask" user "Board Geometry/Soldermask Top")
		(3 "B.Mask" user "Board Geometry/Soldermask Bottom")
		(17 "Dwgs.User" user "User.Drawings")
		(19 "Cmts.User" user "User.Comments")
		(21 "Eco1.User" user "User.Eco1")
		(23 "Eco2.User" user "User.Eco2")
		(25 "Edge.Cuts" user "Board Geometry/Outline")
		(27 "Margin" user)
		(31 "F.CrtYd" user "Package Geometry/Place Bound Top")
		(29 "B.CrtYd" user "Package Geometry/Place Bound Bottom")
		(35 "F.Fab" user "Ref Des/Assembly Top")
		(33 "B.Fab" user "Ref Des/Assembly Bottom")
	)
	(footprint ""
		(layer "B.Cu")
		(at 27.682444 -99.448112 45)
		(property "Reference" "C266"
			(at 0 0 45)
			(layer "B.SilkS")
			(hide yes)
			(effects
				(font
					(size 1.27 1.27)
				)
				(justify mirror)
			)
		)
		(property "Value" ""
			(at 0 0 45)
			(layer "B.Fab")
			(effects
				(font
					(size 1.27 1.27)
				)
				(justify mirror)
			)
		)
		(duplicate_pad_numbers_are_jumpers no)
		(fp_line
			(start -0.787389 -0.406267)
			(end -0.787389 0.406267)
			(stroke
				(width 0.1524)
				(type default)
			)
			(layer "B.SilkS")
		)
		(fp_line
			(start -0.787389 0.406267)
			(end 0.787389 0.406267)
			(stroke
				(width 0.1524)
				(type default)
			)
			(layer "B.SilkS")
		)
		(fp_line
			(start 0.787389 -0.406267)
			(end -0.787389 -0.406267)
			(stroke
				(width 0.1524)
				(type default)
			)
			(layer "B.SilkS")
		)
		(fp_line
			(start 0.787389 0.406267)
			(end 0.787389 -0.406267)
			(stroke
				(width 0.1524)
				(type default)
			)
			(layer "B.SilkS")
		)
		(fp_line
			(start -0.679446 -0.30479)
			(end -0.679446 0.30479)
			(stroke
				(width 0.1)
				(type default)
			)
			(layer "B.Fab")
		)
		(fp_line
			(start -0.120515 -0.30479)
			(end -0.679446 -0.30479)
			(stroke
				(width 0.1)
				(type default)
			)
			(layer "B.Fab")
		)
		(fp_line
			(start -0.120695 -0.279466)
			(end -0.120515 -0.30479)
			(stroke
				(width 0.1)
				(type default)
			)
			(layer "B.Fab")
		)
		(fp_line
			(start -0.679446 0.30479)
			(end -0.120515 0.30479)
			(stroke
				(width 0.1)
				(type default)
			)
			(layer "B.Fab")
		)
		(fp_line
			(start 0.120695 -0.304969)
			(end 0.120695 -0.279466)
			(stroke
				(width 0.1)
				(type default)
			)
			(layer "B.Fab")
		)
		(fp_line
			(start 0.120695 -0.279466)
			(end -0.120695 -0.279466)
			(stroke
				(width 0.1)
				(type default)
			)
			(layer "B.Fab")
		)
		(fp_line
			(start -0.120335 0.279466)
			(end 0.120695 0.279466)
			(stroke
				(width 0.1)
				(type default)
			)
			(layer "B.Fab")
		)
		(fp_line
			(start -0.120515 0.30479)
			(end -0.120335 0.279466)
			(stroke
				(width 0.1)
				(type default)
			)
			(layer "B.Fab")
		)
		(fp_line
			(start 0.679446 -0.305149)
			(end 0.120695 -0.304969)
			(stroke
				(width 0.1)
				(type default)
			)
			(layer "B.Fab")
		)
		(fp_line
			(start 0.120695 0.279466)
			(end 0.120515 0.30479)
			(stroke
				(width 0.1)
				(type default)
			)
			(layer "B.Fab")
		)
		(fp_line
			(start 0.120515 0.30479)
			(end 0.679446 0.30479)
			(stroke
				(width 0.1)
				(type default)
			)
			(layer "B.Fab")
		)
		(fp_line
			(start 0.679446 0.30479)
			(end 0.679446 -0.305149)
			(stroke
				(width 0.1)
				(type default)
			)
			(layer "B.Fab")
		)
		(pad "1" smd circle
			(at 0.40005 0 225)
			(size 0 0)
			(layers "B.Cu" "B.Mask" "B.Paste")
			(net "PVCCA_AUX_PLD")
		)
		(pad "2" smd circle
			(at -0.40005 0 225)
			(size 0 0)
			(layers "B.Cu" "B.Mask" "B.Paste")
			(net "GND")
		)
	)
	(footprint ""
		(layer "B.Cu")
		(at 24.384 -93.345 180)
		(property "Reference" "C220"
			(at 0 0 0)
			(layer "B.SilkS")
			(hide yes)
			(effects
				(font
					(size 1.27 1.27)
				)
				(justify mirror)
			)
		)
		(property "Value" ""
			(at 0 0 0)
			(layer "B.Fab")
			(effects
				(font
					(size 1.27 1.27)
				)
				(justify mirror)
			)
		)
		(duplicate_pad_numbers_are_jumpers no)
		(fp_line
			(start 0.69215 0.2921)
			(end 0.69215 -0.2921)
			(stroke
				(width 0.1524)
				(type default)
			)
			(layer "B.SilkS")
		)
		(fp_line
			(start 0.69215 -0.2921)
			(end -0.69215 -0.2921)
			(stroke
				(width 0.1524)
				(type default)
			)
			(layer "B.SilkS")
		)
		(fp_line
			(start -0.69215 0.2921)
			(end 0.69215 0.2921)
			(stroke
				(width 0.1524)
				(type default)
			)
			(layer "B.SilkS")
		)
		(fp_line
			(start -0.69215 -0.2921)
			(end -0.69215 0.2921)
			(stroke
				(width 0.1524)
				(type default)
			)
			(layer "B.SilkS")
		)
		(fp_line
			(start 0.51435 0.2794)
			(end 0.51435 -0.2794)
			(stroke
				(width 0.1)
				(type default)
			)
			(layer "B.Fab")
		)
		(fp_line
			(start 0.51435 -0.2794)
			(end -0.51435 -0.2794)
			(stroke
				(width 0.1)
				(type default)
			)
			(layer "B.Fab")
		)
		(fp_line
			(start -0.51435 0.2794)
			(end 0.51435 0.2794)
			(stroke
				(width 0.1)
				(type default)
			)
			(layer "B.Fab")
		)
		(fp_line
			(start -0.51435 -0.2794)
			(end -0.51435 0.2794)
			(stroke
				(width 0.1)
				(type default)
			)
			(layer "B.Fab")
		)
		(pad "1" smd circle
			(at 0.40005 0)
			(size 0 0)
			(layers "B.Cu" "B.Mask" "B.Paste")
			(net "VCCIO4")
		)
		(pad "2" smd circle
			(at -0.40005 0)
			(size 0 0)
			(layers "B.Cu" "B.Mask" "B.Paste")
			(net "GND")
		)
		(zone
			(layer "B.Cu")
			(hatch none 0.5)
			(connect_pads
				(clearance 0)
			)
			(min_thickness 0.25)
			(keepout
				(tracks not_allowed)
				(vias allowed)
				(pads allowed)
				(copperpour not_allowed)
				(footprints allowed)
			)
			(placement
				(enabled no)
				(sheetname "")
			)
			(fill
				(thermal_gap 0.5)
				(thermal_bridge_width 0.5)
				(island_removal_mode 0)
			)
			(polygon
				(pts
					(xy 24.1935 -93.43263) (xy 24.28494 -93.490796) (xy 24.48433 -93.490796) (xy 24.5745 -93.43263)
					(xy 24.5745 -93.25737) (xy 24.48433 -93.19895) (xy 24.28494 -93.19895) (xy 24.1935 -93.257116)
				)
			)
		)
	)
	(footprint ""
		(layer "B.Cu")
		(at 12.192 -24.384 -90)
		(property "Reference" "R306"
			(at 0 0 90)
			(layer "B.SilkS")
			(hide yes)
			(effects
				(font
					(size 1.27 1.27)
				)
				(justify mirror)
			)
		)
		(property "Value" ""
			(at 0 0 90)
			(layer "B.Fab")
			(effects
				(font
					(size 1.27 1.27)
				)
				(justify mirror)
			)
		)
		(duplicate_pad_numbers_are_jumpers no)
		(fp_line
			(start -0.7874 0.4064)
			(end 0.7874 0.4064)
			(stroke
				(width 0.1524)
				(type default)
			)
			(layer "B.SilkS")
		)
		(fp_line
			(start 0.7874 0.4064)
			(end 0.7874 -0.4064)
			(stroke
				(width 0.1524)
				(type default)
			)
			(layer "B.SilkS")
		)
		(fp_line
			(start -0.7874 -0.4064)
			(end -0.7874 0.4064)
			(stroke
				(width 0.1524)
				(type default)
			)
			(layer "B.SilkS")
		)
		(fp_line
			(start 0.7874 -0.4064)
			(end -0.7874 -0.4064)
			(stroke
				(width 0.1524)
				(type default)
			)
			(layer "B.SilkS")
		)
		(fp_line
			(start -0.67945 0.3048)
			(end -0.120396 0.3048)
			(stroke
				(width 0.1)
				(type default)
			)
			(layer "B.Fab")
		)
		(fp_line
			(start -0.120396 0.3048)
			(end -0.120396 0.2794)
			(stroke
				(width 0.1)
				(type default)
			)
			(layer "B.Fab")
		)
		(fp_line
			(start 0.12065 0.3048)
			(end 0.67945 0.3048)
			(stroke
				(width 0.1)
				(type default)
			)
			(layer "B.Fab")
		)
		(fp_line
			(start 0.67945 0.3048)
			(end 0.67945 -0.305054)
			(stroke
				(width 0.1)
				(type default)
			)
			(layer "B.Fab")
		)
		(fp_line
			(start -0.120396 0.2794)
			(end 0.12065 0.2794)
			(stroke
				(width 0.1)
				(type default)
			)
			(layer "B.Fab")
		)
		(fp_line
			(start 0.12065 0.2794)
			(end 0.12065 0.3048)
			(stroke
				(width 0.1)
				(type default)
			)
			(layer "B.Fab")
		)
		(fp_line
			(start -0.12065 -0.2794)
			(end -0.12065 -0.3048)
			(stroke
				(width 0.1)
				(type default)
			)
			(layer "B.Fab")
		)
		(fp_line
			(start 0.12065 -0.2794)
			(end -0.12065 -0.2794)
			(stroke
				(width 0.1)
				(type default)
			)
			(layer "B.Fab")
		)
		(fp_line
			(start -0.67945 -0.3048)
			(end -0.67945 0.3048)
			(stroke
				(width 0.1)
				(type default)
			)
			(layer "B.Fab")
		)
		(fp_line
			(start -0.12065 -0.3048)
			(end -0.67945 -0.3048)
			(stroke
				(width 0.1)
				(type default)
			)
			(layer "B.Fab")
		)
		(fp_line
			(start 0.12065 -0.305054)
			(end 0.12065 -0.2794)
			(stroke
				(width 0.1)
				(type default)
			)
			(layer "B.Fab")
		)
		(fp_line
			(start 0.67945 -0.305054)
			(end 0.12065 -0.305054)
			(stroke
				(width 0.1)
				(type default)
			)
			(layer "B.Fab")
		)
		(pad "1" smd circle
			(at 0.40005 0 90)
			(size 0 0)
			(layers "B.Cu" "B.Mask" "B.Paste")
			(net "BEEP_LED")
		)
		(pad "2" smd circle
			(at -0.40005 0 90)
			(size 0 0)
			(layers "B.Cu" "B.Mask" "B.Paste")
			(net "GND")
		)
	)
	(footprint ""
		(layer "B.Cu")
		(at 58.092848 -49.54778 -90)
		(property "Reference" "C93"
			(at 0 0 90)
			(layer "B.SilkS")
			(hide yes)
			(effects
				(font
					(size 1.27 1.27)
				)
				(justify mirror)
			)
		)
		(property "Value" ""
			(at 0 0 90)
			(layer "B.Fab")
			(effects
				(font
					(size 1.27 1.27)
				)
				(justify mirror)
			)
		)
		(duplicate_pad_numbers_are_jumpers no)
		(fp_line
			(start -0.7874 0.4064)
			(end 0.7874 0.4064)
			(stroke
				(width 0.1524)
				(type default)
			)
			(layer "B.SilkS")
		)
		(fp_line
			(start 0.7874 0.4064)
			(end 0.7874 -0.4064)
			(stroke
				(width 0.1524)
				(type default)
			)
			(layer "B.SilkS")
		)
		(fp_line
			(start -0.7874 -0.4064)
			(end -0.7874 0.4064)
			(stroke
				(width 0.1524)
				(type default)
			)
			(layer "B.SilkS")
		)
		(fp_line
			(start 0.7874 -0.4064)
			(end -0.7874 -0.4064)
			(stroke
				(width 0.1524)
				(type default)
			)
			(layer "B.SilkS")
		)
		(fp_line
			(start -0.67945 0.3048)
			(end -0.120396 0.3048)
			(stroke
				(width 0.1)
				(type default)
			)
			(layer "B.Fab")
		)
		(fp_line
			(start -0.120396 0.3048)
			(end -0.120396 0.2794)
			(stroke
				(width 0.1)
				(type default)
			)
			(layer "B.Fab")
		)
		(fp_line
			(start 0.12065 0.3048)
			(end 0.67945 0.3048)
			(stroke
				(width 0.1)
				(type default)
			)
			(layer "B.Fab")
		)
		(fp_line
			(start 0.67945 0.3048)
			(end 0.67945 -0.305054)
			(stroke
				(width 0.1)
				(type default)
			)
			(layer "B.Fab")
		)
		(fp_line
			(start -0.120396 0.2794)
			(end 0.12065 0.2794)
			(stroke
				(width 0.1)
				(type default)
			)
			(layer "B.Fab")
		)
		(fp_line
			(start 0.12065 0.2794)
			(end 0.12065 0.3048)
			(stroke
				(width 0.1)
				(type default)
			)
			(layer "B.Fab")
		)
		(fp_line
			(start -0.12065 -0.2794)
			(end -0.12065 -0.3048)
			(stroke
				(width 0.1)
				(type default)
			)
			(layer "B.Fab")
		)
		(fp_line
			(start 0.12065 -0.2794)
			(end -0.12065 -0.2794)
			(stroke
				(width 0.1)
				(type default)
			)
			(layer "B.Fab")
		)
		(fp_line
			(start -0.67945 -0.3048)
			(end -0.67945 0.3048)
			(stroke
				(width 0.1)
				(type default)
			)
			(layer "B.Fab")
		)
		(fp_line
			(start -0.12065 -0.3048)
			(end -0.67945 -0.3048)
			(stroke
				(width 0.1)
				(type default)
			)
			(layer "B.Fab")
		)
		(fp_line
			(start 0.12065 -0.305054)
			(end 0.12065 -0.2794)
			(stroke
				(width 0.1)
				(type default)
			)
			(layer "B.Fab")
		)
		(fp_line
			(start 0.67945 -0.305054)
			(end 0.12065 -0.305054)
			(stroke
				(width 0.1)
				(type default)
			)
			(layer "B.Fab")
		)
		(pad "1" smd circle
			(at 0.40005 0 90)
			(size 0 0)
			(layers "B.Cu" "B.Mask" "B.Paste")
			(net "P1V8_AUX")
		)
		(pad "2" smd circle
			(at -0.40005 0 90)
			(size 0 0)
			(layers "B.Cu" "B.Mask" "B.Paste")
			(net "GND")
		)
	)
	(footprint ""
		(layer "B.Cu")
		(at 43.5356 -4.1148 -90)
		(property "Reference" "U26"
			(at -2.047748 -2.3876 0)
			(unlocked yes)
			(layer "B.SilkS")
			(effects
				(font
					(size 0.7874 0.5842)
					(thickness 0.1524)
				)
				(justify left mirror)
			)
		)
		(property "Value" ""
			(at 0 0 90)
			(layer "B.Fab")
			(effects
				(font
					(size 1.27 1.27)
				)
				(justify mirror)
			)
		)
		(duplicate_pad_numbers_are_jumpers no)
		(fp_line
			(start -1.3462 1.1938)
			(end -1.3462 -1.1938)
			(stroke
				(width 0.1524)
				(type default)
			)
			(layer "B.SilkS")
		)
		(fp_line
			(start 1.3462 1.1938)
			(end -1.3462 1.1938)
			(stroke
				(width 0.1524)
				(type default)
			)
			(layer "B.SilkS")
		)
		(fp_line
			(start -1.3462 -1.1938)
			(end 1.3462 -1.1938)
			(stroke
				(width 0.1524)
				(type default)
			)
			(layer "B.SilkS")
		)
		(fp_line
			(start 1.3462 -1.1938)
			(end 1.3462 1.1684)
			(stroke
				(width 0.1524)
				(type default)
			)
			(layer "B.SilkS")
		)
		(fp_poly
			(pts
				(xy 1.447038 -0.760476) (xy 2.052066 -0.457962) (xy 2.052066 -1.06299)
			)
			(stroke
				(width 0)
				(type default)
			)
			(fill yes)
			(layer "B.SilkS")
		)
		(fp_line
			(start -0.674878 1.124966)
			(end -0.674878 -1.124966)
			(stroke
				(width 0.1)
				(type default)
			)
			(layer "B.Fab")
		)
		(fp_line
			(start 0.674878 1.124966)
			(end -0.674878 1.124966)
			(stroke
				(width 0.1)
				(type default)
			)
			(layer "B.Fab")
		)
		(fp_line
			(start -0.674878 -1.124966)
			(end 0.674878 -1.124966)
			(stroke
				(width 0.1)
				(type default)
			)
			(layer "B.Fab")
		)
		(fp_line
			(start 0.674878 -1.124966)
			(end 0.674878 1.124966)
			(stroke
				(width 0.1)
				(type default)
			)
			(layer "B.Fab")
		)
		(fp_poly
			(pts
				(xy 1.447038 -0.760476) (xy 2.052066 -0.457962) (xy 2.052066 -1.06299)
			)
			(stroke
				(width 0)
				(type default)
			)
			(fill yes)
			(layer "B.Fab")
		)
		(pad "1" smd rect
			(at 0.899922 -0.750062 90)
			(size 0.6096 0.6096)
			(layers "B.Cu" "B.Mask" "B.Paste")
			(net "BMC_DDC_BUF_EN")
		)
		(pad "2" smd rect
			(at 0.899922 0)
			(size 0.4064 0.6096)
			(layers "B.Cu" "B.Mask" "B.Paste")
			(net "V_VGAVS")
		)
		(pad "3" smd rect
			(at 0.899922 0.750062 90)
			(size 0.6096 0.6096)
			(layers "B.Cu" "B.Mask" "B.Paste")
			(net "GND")
		)
		(pad "4" smd rect
			(at -0.899922 0.750062 90)
			(size 0.6096 0.6096)
			(layers "B.Cu" "B.Mask" "B.Paste")
			(net "V_VGAVS_BUF_R")
		)
		(pad "5" smd rect
			(at -0.899922 -0.750062 90)
			(size 0.6096 0.6096)
			(layers "B.Cu" "B.Mask" "B.Paste")
			(net "BMC_DDC_BUF_PWR")
		)
	)
	(footprint ""
		(layer "B.Cu")
		(at 50.508662 -46.220126 180)
		(property "Reference" "C32"
			(at 0 0 0)
			(layer "B.SilkS")
			(hide yes)
			(effects
				(font
					(size 1.27 1.27)
				)
				(justify mirror)
			)
		)
		(property "Value" ""
			(at 0 0 0)
			(layer "B.Fab")
			(effects
				(font
					(size 1.27 1.27)
				)
				(justify mirror)
			)
		)
		(duplicate_pad_numbers_are_jumpers no)
		(fp_line
			(start 0.7874 0.4064)
			(end 0.7874 -0.4064)
			(stroke
				(width 0.1524)
				(type default)
			)
			(layer "B.SilkS")
		)
		(fp_line
			(start 0.7874 -0.4064)
			(end -0.7874 -0.4064)
			(stroke
				(width 0.1524)
				(type default)
			)
			(layer "B.SilkS")
		)
		(fp_line
			(start -0.7874 0.4064)
			(end 0.7874 0.4064)
			(stroke
				(width 0.1524)
				(type default)
			)
			(layer "B.SilkS")
		)
		(fp_line
			(start -0.7874 -0.4064)
			(end -0.7874 0.4064)
			(stroke
				(width 0.1524)
				(type default)
			)
			(layer "B.SilkS")
		)
		(fp_line
			(start 0.67945 0.3048)
			(end 0.67945 -0.305054)
			(stroke
				(width 0.1)
				(type default)
			)
			(layer "B.Fab")
		)
		(fp_line
			(start 0.67945 -0.305054)
			(end 0.12065 -0.305054)
			(stroke
				(width 0.1)
				(type default)
			)
			(layer "B.Fab")
		)
		(fp_line
			(start 0.12065 0.3048)
			(end 0.67945 0.3048)
			(stroke
				(width 0.1)
				(type default)
			)
			(layer "B.Fab")
		)
		(fp_line
			(start 0.12065 0.2794)
			(end 0.12065 0.3048)
			(stroke
				(width 0.1)
				(type default)
			)
			(layer "B.Fab")
		)
		(fp_line
			(start 0.12065 -0.2794)
			(end -0.12065 -0.2794)
			(stroke
				(width 0.1)
				(type default)
			)
			(layer "B.Fab")
		)
		(fp_line
			(start 0.12065 -0.305054)
			(end 0.12065 -0.2794)
			(stroke
				(width 0.1)
				(type default)
			)
			(layer "B.Fab")
		)
		(fp_line
			(start -0.120396 0.3048)
			(end -0.120396 0.2794)
			(stroke
				(width 0.1)
				(type default)
			)
			(layer "B.Fab")
		)
		(fp_line
			(start -0.120396 0.2794)
			(end 0.12065 0.2794)
			(stroke
				(width 0.1)
				(type default)
			)
			(layer "B.Fab")
		)
		(fp_line
			(start -0.12065 -0.2794)
			(end -0.12065 -0.3048)
			(stroke
				(width 0.1)
				(type default)
			)
			(layer "B.Fab")
		)
		(fp_line
			(start -0.12065 -0.3048)
			(end -0.67945 -0.3048)
			(stroke
				(width 0.1)
				(type default)
			)
			(layer "B.Fab")
		)
		(fp_line
			(start -0.67945 0.3048)
			(end -0.120396 0.3048)
			(stroke
				(width 0.1)
				(type default)
			)
			(layer "B.Fab")
		)
		(fp_line
			(start -0.67945 -0.3048)
			(end -0.67945 0.3048)
			(stroke
				(width 0.1)
				(type default)
			)
			(layer "B.Fab")
		)
		(pad "1" smd circle
			(at 0.40005 0)
			(size 0 0)
			(layers "B.Cu" "B.Mask" "B.Paste")
			(net "P3V3_P2V5_P1V8_RVDD")
		)
		(pad "2" smd circle
			(at -0.40005 0)
			(size 0 0)
			(layers "B.Cu" "B.Mask" "B.Paste")
			(net "GND")
		)
	)
)
